# T6G (Grand Teton) — schematic netlist excerpt (pin names and nets, part order shuffled) for the footprints in the layout excerpt that follows; sources: Cadence DE-HDL packaged netlist, KiCad conversion of 04192023_DAF0TMB3IC0_F0TG_MB_C_brd_V02_OCP.brd

PU27  ISL99390FRZTR5935  ISL99390FRZ-TR5935 IC  pkg QFN21_6X5XB  page 212
  VOS  = PVDDCR_CPU0_P1_VOS3
  AGND  = GND
  VCC  = PVDDCR_CPU0_P1_VCC3
  PVCC  = PVDDCR_CPU0_P1_PVCC
  PGND1  = GND
  GL1  = NC_PVDDCR_CPU0_P1_GL1_3
  PGND2  = GND
  SW  = SW_PVDDCR_CPU0_P1_SW3
  VIN1  = SW_P12V_AUX_PVDDCR_CPU0_P1_FLT
  VIN2  = SW_P12V_AUX_PVDDCR_CPU0_P1_FLT
  DNC  = NC_PVDDCR_CPU0_P1_DNC3
  PHASE  = SW_PVDDCR_CPU0_P1_PH3
  BOOT  = SW_PVDDCR_CPU0_P1_BOOT3
  PWM  = PVDDCR_CPU0_P1_PWM3
  EN  = PVDDCR_CPU0_P1_VCC3
  TOUT_FLT  = PVDDCR_CPU0_P1_TEMP0
  LSET  = PVDDCR_CPU0_P1_LSET3
  IOUT  = PVDDCR_CPU0_P1_IMON3
  REFIN  = PVDDCR_CPU0_P1_VCCS
  PGND3  = GND
  GL2  = NC_PVDDCR_CPU0_P1_GL2_3

(kicad_pcb
	(version 20260206)
	(generator "pcbnew")
	(generator_version "10.0")
	(general
		(thickness 1.6)
		(legacy_teardrops no)
	)
	(paper "A4")
	(title_block
		(title "04192023_DAF0TMB3IC0_F0TG_MB_C_brd_V02_OCP.brd")
		(comment 1 "Grand Teton / footprints 4861-4861 of 8354")
	)
	(layers
		(0 "F.Cu" signal "TOP")
		(4 "In1.Cu" signal "GND")
		(6 "In2.Cu" signal "IN1")
		(8 "In3.Cu" signal "GND1")
		(10 "In4.Cu" signal "IN2")
		(12 "In5.Cu" signal "GND2")
		(14 "In6.Cu" signal "IN3")
		(16 "In7.Cu" signal "GND3")
		(18 "In8.Cu" signal "VCC")
		(20 "In9.Cu" signal "VCC1")
		(22 "In10.Cu" signal "GND4")
		(24 "In11.Cu" signal "IN4")
		(26 "In12.Cu" signal "GND5")
		(28 "In13.Cu" signal "IN5")
		(30 "In14.Cu" signal "GND6")
		(32 "In15.Cu" signal "IN6")
		(34 "In16.Cu" signal "GND7")
		(2 "B.Cu" signal "BOTTOM")
		(9 "F.Adhes" user "F.Adhesive")
		(11 "B.Adhes" user "B.Adhesive")
		(13 "F.Paste" user "Package Geometry/Pastemask Top")
		(15 "B.Paste" user "Package Geometry/Pastemask Bottom")
		(5 "F.SilkS" user "Ref Des/Silkscreen Top")
		(7 "B.SilkS" user "Ref Des/Silkscreen Bottom")
		(1 "F.Mask" user "Board Geometry/Soldermask Top")
		(3 "B.Mask" user "Board Geometry/Soldermask Bottom")
		(17 "Dwgs.User" user "User.Drawings")
		(19 "Cmts.User" user "User.Comments")
		(21 "Eco1.User" user "User.Eco1")
		(23 "Eco2.User" user "User.Eco2")
		(25 "Edge.Cuts" user "Board Geometry/Outline")
		(27 "Margin" user)
		(31 "F.CrtYd" user "Package Geometry/Place Bound Top")
		(29 "B.CrtYd" user "Package Geometry/Place Bound Bottom")
		(35 "F.Fab" user "Ref Des/Assembly Top")
		(33 "B.Fab" user "Ref Des/Assembly Bottom")
	)
	(footprint ""
		(layer "F.Cu")
		(at 99.07397 -182.693056 180)
		(property "Reference" "PU27"
			(at 0.78994 -6.592062 0)
			(unlocked yes)
			(layer "F.SilkS")
			(effects
				(font
					(size 0.7874 0.5842)
					(thickness 0.1524)
				)
				(justify left)
			)
		)
		(property "Value" ""
			(at 0 0 180)
			(layer "F.Fab")
			(effects
				(font
					(size 1.27 1.27)
				)
			)
		)
		(duplicate_pad_numbers_are_jumpers no)
		(fp_line
			(start 2.500122 2.999994)
			(end 2.2987 2.999994)
			(stroke
				(width 0.1524)
				(type default)
			)
			(layer "F.SilkS")
		)
		(fp_line
			(start 2.500122 2.339594)
			(end 2.500122 2.999994)
			(stroke
				(width 0.1524)
				(type default)
			)
			(layer "F.SilkS")
		)
		(fp_line
			(start 2.500122 -2.999994)
			(end 2.500122 -2.44348)
			(stroke
				(width 0.1524)
				(type default)
			)
			(layer "F.SilkS")
		)
		(fp_line
			(start 2.31394 -2.999994)
			(end 2.500122 -2.999994)
			(stroke
				(width 0.1524)
				(type default)
			)
			(layer "F.SilkS")
		)
		(fp_line
			(start -2.2987 2.999994)
			(end -2.500122 2.999994)
			(stroke
				(width 0.1524)
				(type default)
			)
			(layer "F.SilkS")
		)
		(fp_line
			(start -2.500122 2.999994)
			(end -2.500122 2.339594)
			(stroke
				(width 0.1524)
				(type default)
			)
			(layer "F.SilkS")
		)
		(fp_line
			(start -2.500122 0.6604)
			(end -2.500122 0.229108)
			(stroke
				(width 0.1524)
				(type default)
			)
			(layer "F.SilkS")
		)
		(fp_line
			(start -2.500122 -2.529078)
			(end -2.500122 -2.999994)
			(stroke
				(width 0.1524)
				(type default)
			)
			(layer "F.SilkS")
		)
		(fp_line
			(start -2.500122 -2.999994)
			(end -2.24409 -2.999994)
			(stroke
				(width 0.1524)
				(type default)
			)
			(layer "F.SilkS")
		)
		(fp_poly
			(pts
				(xy -2.770632 -2.436368) (xy -3.443986 -2.660904) (xy -2.995168 -3.109722)
			)
			(stroke
				(width 0)
				(type default)
			)
			(fill yes)
			(layer "F.SilkS")
		)
		(fp_line
			(start 2.500122 2.999994)
			(end -2.500122 2.999994)
			(stroke
				(width 0.1)
				(type default)
			)
			(layer "F.Fab")
		)
		(fp_line
			(start 2.500122 -2.999994)
			(end 2.500122 2.999994)
			(stroke
				(width 0.1)
				(type default)
			)
			(layer "F.Fab")
		)
		(fp_line
			(start -2.500122 2.999994)
			(end -2.500122 -2.999994)
			(stroke
				(width 0.1)
				(type default)
			)
			(layer "F.Fab")
		)
		(fp_line
			(start -2.500122 -2.999994)
			(end 2.500122 -2.999994)
			(stroke
				(width 0.1)
				(type default)
			)
			(layer "F.Fab")
		)
		(fp_poly
			(pts
				(xy -4.218432 -2.783078) (xy -4.218432 -1.767078) (xy -3.202432 -2.275078)
			)
			(stroke
				(width 0)
				(type default)
			)
			(fill yes)
			(layer "F.Fab")
		)
		(pad "1" smd rect
			(at -2.400046 -2.275078 270)
			(size 0.2286 0.6096)
			(layers "F.Cu" "F.Mask" "F.Paste")
			(net "PVDDCR_CPU0_P1_VOS3")
		)
		(pad "2" smd rect
			(at -2.400046 -1.82499 270)
			(size 0.2286 0.6096)
			(layers "F.Cu" "F.Mask" "F.Paste")
			(net "GND")
		)
		(pad "3" smd rect
			(at -2.400046 -1.374902 270)
			(size 0.2286 0.6096)
			(layers "F.Cu" "F.Mask" "F.Paste")
			(net "PVDDCR_CPU0_P1_VCC3")
		)
		(pad "4" smd rect
			(at -2.400046 -0.925068 270)
			(size 0.2286 0.6096)
			(layers "F.Cu" "F.Mask" "F.Paste")
			(net "PVDDCR_CPU0_P1_PVCC")
		)
		(pad "5" smd rect
			(at -2.400046 -0.47498 270)
			(size 0.2286 0.6096)
			(layers "F.Cu" "F.Mask" "F.Paste")
			(net "GND")
		)
		(pad "6" smd rect
			(at -2.400046 -0.024892 270)
			(size 0.2286 0.6096)
			(layers "F.Cu" "F.Mask" "F.Paste")
			(net "NC_PVDDCR_CPU0_P1_GL1_3")
		)
		(pad "7_9-20_24" smd circle
			(at 0 1.150112 270)
			(size 0 0)
			(layers "F.Cu" "F.Mask" "F.Paste")
			(net "GND")
		)
		(pad "10_19" smd rect
			(at 0 2.899918 270)
			(size 0.6096 4.318)
			(layers "F.Cu" "F.Mask" "F.Paste")
			(net "SW_PVDDCR_CPU0_P1_SW3")
		)
		(pad "25_29" smd rect
			(at 1.549908 -1.279906 90)
			(size 2.0574 2.3114)
			(layers "F.Cu" "F.Mask" "F.Paste")
			(net "SW_P12V_AUX_PVDDCR_CPU0_P1_FLT")
		)
		(pad "30" smd rect
			(at 2.05994 -2.899918 180)
			(size 0.2286 0.6096)
			(layers "F.Cu" "F.Mask" "F.Paste")
			(net "SW_P12V_AUX_PVDDCR_CPU0_P1_FLT")
		)
		(pad "31" smd rect
			(at 1.610106 -2.899918 180)
			(size 0.2286 0.6096)
			(layers "F.Cu" "F.Mask" "F.Paste")
			(net "NC_PVDDCR_CPU0_P1_DNC3")
		)
		(pad "32" smd rect
			(at 1.160018 -2.899918 180)
			(size 0.2286 0.6096)
			(layers "F.Cu" "F.Mask" "F.Paste")
			(net "SW_PVDDCR_CPU0_P1_PH3")
		)
		(pad "33" smd rect
			(at 0.70993 -2.899918 180)
			(size 0.2286 0.6096)
			(layers "F.Cu" "F.Mask" "F.Paste")
			(net "SW_PVDDCR_CPU0_P1_BOOT3")
		)
		(pad "34" smd rect
			(at 0.260096 -2.899918 180)
			(size 0.2286 0.6096)
			(layers "F.Cu" "F.Mask" "F.Paste")
			(net "PVDDCR_CPU0_P1_PWM3")
		)
		(pad "35" smd rect
			(at -0.189992 -2.899918 180)
			(size 0.2286 0.6096)
			(layers "F.Cu" "F.Mask" "F.Paste")
			(net "PVDDCR_CPU0_P1_VCC3")
		)
		(pad "36" smd rect
			(at -0.64008 -2.899918 180)
			(size 0.2286 0.6096)
			(layers "F.Cu" "F.Mask" "F.Paste")
			(net "PVDDCR_CPU0_P1_TEMP0")
		)
		(pad "37" smd rect
			(at -1.089914 -2.899918 180)
			(size 0.2286 0.6096)
			(layers "F.Cu" "F.Mask" "F.Paste")
			(net "PVDDCR_CPU0_P1_LSET3")
		)
		(pad "38" smd rect
			(at -1.540002 -2.899918 180)
			(size 0.2286 0.6096)
			(layers "F.Cu" "F.Mask" "F.Paste")
			(net "PVDDCR_CPU0_P1_IMON3")
		)
		(pad "39" smd rect
			(at -1.99009 -2.899918 180)
			(size 0.2286 0.6096)
			(layers "F.Cu" "F.Mask" "F.Paste")
			(net "PVDDCR_CPU0_P1_VCCS")
		)
		(pad "40" smd rect
			(at -0.87503 -1.27508 180)
			(size 1.7526 1.9558)
			(layers "F.Cu" "F.Mask" "F.Paste")
			(net "GND")
		)
		(pad "41" smd rect
			(at -1.525016 0.249936 90)
			(size 0.3048 0.4572)
			(layers "F.Cu" "F.Mask" "F.Paste")
			(net "NC_PVDDCR_CPU0_P1_GL2_3")
		)
		(zone
			(layer "F.Cu")
			(hatch none 0.5)
			(connect_pads
				(clearance 0)
			)
			(min_thickness 0.25)
			(keepout
				(tracks not_allowed)
				(vias allowed)
				(pads allowed)
				(copperpour not_allowed)
				(footprints allowed)
			)
			(placement
				(enabled no)
				(sheetname "")
			)
			(fill
				(thermal_gap 0.5)
				(thermal_bridge_width 0.5)
				(island_removal_mode 0)
			)
			(polygon
				(pts
					(xy 101.574092 -185.237374) (xy 101.574092 -184.94375) (xy 96.573848 -184.94375) (xy 96.573848 -185.237374)
					(xy 96.86417 -185.237374) (xy 101.28377 -185.237374)
				)
			)
		)
		(zone
			(layer "F.Cu")
			(hatch none 0.5)
			(connect_pads
				(clearance 0)
			)
			(min_thickness 0.25)
			(keepout
				(tracks not_allowed)
				(vias allowed)
				(pads allowed)
				(copperpour not_allowed)
				(footprints allowed)
			)
			(placement
				(enabled no)
				(sheetname "")
			)
			(fill
				(thermal_gap 0.5)
				(thermal_bridge_width 0.5)
				(island_removal_mode 0)
			)
			(polygon
				(pts
					(xy 99.0219 -182.446676) (xy 99.0219 -180.389276) (xy 100.8761 -180.389276) (xy 100.8761 -180.630322)
					(xy 101.118416 -180.630322) (xy 101.118416 -180.148738) (xy 97.178368 -180.148738) (xy 97.178368 -180.33365)
					(xy 98.730562 -180.33365) (xy 98.730562 -182.49265) (xy 96.573848 -182.49265) (xy 96.573848 -182.742332)
					(xy 98.726244 -182.742332)
				)
			)
		)
	)
)
